(kicad_pcb
	(version 20260206)
	(generator "pcbnew")
	(generator_version "10.0")
	(general
		(thickness 1.6)
		(legacy_teardrops no)
	)
	(paper "A4")
	(title_block
		(title "v2-tray-backplane — ms_tbp_v2.brd")
		(comment 1 "Open CloudServer (Microsoft) / footprints 28-36 of 164")
	)
	(layers
		(0 "F.Cu" signal "TOP")
		(4 "In1.Cu" signal "LYR2")
		(6 "In2.Cu" signal "LYR3")
		(8 "In3.Cu" signal "LYR4")
		(10 "In4.Cu" signal "LYR5")
		(12 "In5.Cu" signal "LYR6")
		(14 "In6.Cu" signal "LYR7")
		(2 "B.Cu" signal "BOTTOM")
		(9 "F.Adhes" user "F.Adhesive")
		(11 "B.Adhes" user "B.Adhesive")
		(13 "F.Paste" user "Package Geometry/Pastemask Top")
		(15 "B.Paste" user "Package Geometry/Pastemask Bottom")
		(5 "F.SilkS" user "Ref Des/Silkscreen Top")
		(7 "B.SilkS" user "Ref Des/Silkscreen Bottom")
		(1 "F.Mask" user "Board Geometry/Soldermask Top")
		(3 "B.Mask" user "Board Geometry/Soldermask Bottom")
		(17 "Dwgs.User" user "User.Drawings")
		(19 "Cmts.User" user "User.Comments")
		(21 "Eco1.User" user "User.Eco1")
		(23 "Eco2.User" user "User.Eco2")
		(25 "Edge.Cuts" user "Board Geometry/Outline")
		(27 "Margin" user)
		(31 "F.CrtYd" user "Package Geometry/Place Bound Top")
		(29 "B.CrtYd" user "Package Geometry/Place Bound Bottom")
		(35 "F.Fab" user "Ref Des/Assembly Top")
		(33 "B.Fab" user "Ref Des/Assembly Bottom")
	)
	(footprint ""
		(layer "F.Cu")
		(at -110.5462 3.0226 -90)
		(property "Reference" "J28"
			(at 0.6858 -4.00082 90)
			(unlocked yes)
			(layer "F.SilkS")
			(effects
				(font
					(size 0.762 0.5334)
					(thickness 0.1016)
				)
			)
		)
		(property "Value" ""
			(at 0 0 270)
			(layer "F.Fab")
			(effects
				(font
					(size 1.27 1.27)
				)
			)
		)
		(duplicate_pad_numbers_are_jumpers no)
		(fp_line
			(start -2.54 1.27)
			(end 0.127 1.27)
			(stroke
				(width 0.127)
				(type default)
			)
			(layer "F.SilkS")
		)
		(fp_line
			(start 2.443175 1.257198)
			(end 2.570175 1.257198)
			(stroke
				(width 0.127)
				(type default)
			)
			(layer "F.SilkS")
		)
		(fp_line
			(start 2.570175 1.257198)
			(end 2.570175 -1.282802)
			(stroke
				(width 0.127)
				(type default)
			)
			(layer "F.SilkS")
		)
		(fp_line
			(start -2.54 -1.27)
			(end -2.54 1.27)
			(stroke
				(width 0.127)
				(type default)
			)
			(layer "F.SilkS")
		)
		(fp_line
			(start -2.413 -1.27)
			(end -2.54 -1.27)
			(stroke
				(width 0.127)
				(type default)
			)
			(layer "F.SilkS")
		)
		(fp_line
			(start 2.570175 -1.282802)
			(end -0.096825 -1.282802)
			(stroke
				(width 0.127)
				(type default)
			)
			(layer "F.SilkS")
		)
		(fp_poly
			(pts
				(xy 0.127 3.683) (xy 0.127 1.778) (xy -3.048 1.778) (xy -3.048 -1.778) (xy -2.413 -1.778) (xy -2.413 -3.683)
				(xy -0.127 -3.683) (xy -0.127 -1.778) (xy 3.048 -1.778) (xy 3.048 1.778) (xy 2.413 1.778) (xy 2.413 3.683)
			)
			(stroke
				(width 0)
				(type default)
			)
			(fill no)
			(layer "F.CrtYd")
		)
		(fp_line
			(start -2.54 1.27)
			(end -2.54 -1.27)
			(stroke
				(width 0.1)
				(type default)
			)
			(layer "F.Fab")
		)
		(fp_line
			(start 2.54 1.27)
			(end -2.54 1.27)
			(stroke
				(width 0.1)
				(type default)
			)
			(layer "F.Fab")
		)
		(fp_line
			(start -2.54 -1.27)
			(end 2.54 -1.27)
			(stroke
				(width 0.1)
				(type default)
			)
			(layer "F.Fab")
		)
		(fp_line
			(start 2.54 -1.27)
			(end 2.54 1.27)
			(stroke
				(width 0.1)
				(type default)
			)
			(layer "F.Fab")
		)
		(fp_text user "*"
			(at -1.27 -3.89255 90)
			(unlocked yes)
			(layer "F.SilkS")
			(effects
				(font
					(size 0.381 0.381)
					(thickness 0.381)
				)
			)
		)
		(pad "1" smd rect
			(at -1.27 -1.4605 270)
			(size 1.27 3.429)
			(layers "F.Cu" "F.Mask" "F.Paste")
			(net "BLADE_B2_EN1")
		)
		(pad "2" smd rect
			(at 1.27 1.4605 270)
			(size 1.27 3.429)
			(layers "F.Cu" "F.Mask" "F.Paste")
			(net "UNNAMED_6_1X2HDR_I52_IO")
		)
	)
	(footprint ""
		(layer "F.Cu")
		(at -118.3694 2.794 -90)
		(property "Reference" "J29"
			(at 0.15748 3.94938 90)
			(unlocked yes)
			(layer "F.SilkS")
			(effects
				(font
					(size 0.762 0.5334)
					(thickness 0.1016)
				)
			)
		)
		(property "Value" ""
			(at 0 0 270)
			(layer "F.Fab")
			(effects
				(font
					(size 1.27 1.27)
				)
			)
		)
		(duplicate_pad_numbers_are_jumpers no)
		(fp_line
			(start -2.54 1.27)
			(end 0.127 1.27)
			(stroke
				(width 0.127)
				(type default)
			)
			(layer "F.SilkS")
		)
		(fp_line
			(start 2.443175 1.257198)
			(end 2.570175 1.257198)
			(stroke
				(width 0.127)
				(type default)
			)
			(layer "F.SilkS")
		)
		(fp_line
			(start 2.570175 1.257198)
			(end 2.570175 -1.282802)
			(stroke
				(width 0.127)
				(type default)
			)
			(layer "F.SilkS")
		)
		(fp_line
			(start -2.54 -1.27)
			(end -2.54 1.27)
			(stroke
				(width 0.127)
				(type default)
			)
			(layer "F.SilkS")
		)
		(fp_line
			(start -2.413 -1.27)
			(end -2.54 -1.27)
			(stroke
				(width 0.127)
				(type default)
			)
			(layer "F.SilkS")
		)
		(fp_line
			(start 2.570175 -1.282802)
			(end -0.096825 -1.282802)
			(stroke
				(width 0.127)
				(type default)
			)
			(layer "F.SilkS")
		)
		(fp_poly
			(pts
				(xy 0.127 3.683) (xy 0.127 1.778) (xy -3.048 1.778) (xy -3.048 -1.778) (xy -2.413 -1.778) (xy -2.413 -3.683)
				(xy -0.127 -3.683) (xy -0.127 -1.778) (xy 3.048 -1.778) (xy 3.048 1.778) (xy 2.413 1.778) (xy 2.413 3.683)
			)
			(stroke
				(width 0)
				(type default)
			)
			(fill no)
			(layer "F.CrtYd")
		)
		(fp_line
			(start -2.54 1.27)
			(end -2.54 -1.27)
			(stroke
				(width 0.1)
				(type default)
			)
			(layer "F.Fab")
		)
		(fp_line
			(start 2.54 1.27)
			(end -2.54 1.27)
			(stroke
				(width 0.1)
				(type default)
			)
			(layer "F.Fab")
		)
		(fp_line
			(start -2.54 -1.27)
			(end 2.54 -1.27)
			(stroke
				(width 0.1)
				(type default)
			)
			(layer "F.Fab")
		)
		(fp_line
			(start 2.54 -1.27)
			(end 2.54 1.27)
			(stroke
				(width 0.1)
				(type default)
			)
			(layer "F.Fab")
		)
		(fp_text user "*"
			(at -1.27 -3.89255 90)
			(unlocked yes)
			(layer "F.SilkS")
			(effects
				(font
					(size 0.381 0.381)
					(thickness 0.381)
				)
			)
		)
		(pad "1" smd rect
			(at -1.27 -1.4605 270)
			(size 1.27 3.429)
			(layers "F.Cu" "F.Mask" "F.Paste")
			(net "PSU_B2_ALERT_N")
		)
		(pad "2" smd rect
			(at 1.27 1.4605 270)
			(size 1.27 3.429)
			(layers "F.Cu" "F.Mask" "F.Paste")
			(net "UNNAMED_6_1X2HDR_I56_IO")
		)
	)
	(footprint ""
		(layer "F.Cu")
		(at -110.8456 13.2334)
		(property "Reference" "R64"
			(at 3.0226 0.0127 0)
			(unlocked yes)
			(layer "F.SilkS")
			(effects
				(font
					(size 0.762 0.5334)
					(thickness 0.1016)
				)
			)
		)
		(property "Value" ""
			(at 0 0 0)
			(layer "F.Fab")
			(effects
				(font
					(size 1.27 1.27)
				)
			)
		)
		(duplicate_pad_numbers_are_jumpers no)
		(fp_line
			(start 0 -0.381)
			(end 0 0.381)
			(stroke
				(width 0.127)
				(type default)
			)
			(layer "F.SilkS")
		)
		(fp_poly
			(pts
				(xy 1.255601 0.6564) (xy -1.255601 0.6564) (xy -1.255601 -0.656399) (xy 1.255601 -0.656399)
			)
			(stroke
				(width 0)
				(type default)
			)
			(fill no)
			(layer "F.CrtYd")
		)
		(fp_line
			(start -0.800001 -0.399999)
			(end -0.800001 0.399999)
			(stroke
				(width 0.1)
				(type default)
			)
			(layer "F.Fab")
		)
		(fp_line
			(start -0.800001 0.399999)
			(end 0.800001 0.399999)
			(stroke
				(width 0.1)
				(type default)
			)
			(layer "F.Fab")
		)
		(fp_line
			(start 0.800001 -0.399999)
			(end -0.800001 -0.399999)
			(stroke
				(width 0.1)
				(type default)
			)
			(layer "F.Fab")
		)
		(fp_line
			(start 0.800001 0.399999)
			(end 0.800001 -0.399999)
			(stroke
				(width 0.1)
				(type default)
			)
			(layer "F.Fab")
		)
		(pad "1" smd rect
			(at -0.650001 0)
			(size 0.7112 0.8128)
			(layers "F.Cu" "F.Mask" "F.Paste")
			(net "P3V3_B2_QSFP")
		)
		(pad "2" smd rect
			(at 0.650001 0 180)
			(size 0.7112 0.8128)
			(layers "F.Cu" "F.Mask" "F.Paste")
			(net "ETH40G_B2_INT_N")
		)
	)
	(footprint ""
		(layer "F.Cu")
		(at -44.8056 8.75538 180)
		(property "Reference" "R58"
			(at -2.8956 -0.04572 0)
			(unlocked yes)
			(layer "F.SilkS")
			(effects
				(font
					(size 0.762 0.5334)
					(thickness 0.1016)
				)
			)
		)
		(property "Value" ""
			(at 0 0 180)
			(layer "F.Fab")
			(effects
				(font
					(size 1.27 1.27)
				)
			)
		)
		(duplicate_pad_numbers_are_jumpers no)
		(fp_line
			(start 0 -0.381)
			(end 0 0.381)
			(stroke
				(width 0.127)
				(type default)
			)
			(layer "F.SilkS")
		)
		(fp_poly
			(pts
				(xy 1.255601 0.656399) (xy -1.255601 0.656399) (xy -1.255601 -0.6564) (xy 1.255601 -0.6564)
			)
			(stroke
				(width 0)
				(type default)
			)
			(fill no)
			(layer "F.CrtYd")
		)
		(fp_line
			(start 0.800001 0.399999)
			(end 0.800001 -0.399999)
			(stroke
				(width 0.1)
				(type default)
			)
			(layer "F.Fab")
		)
		(fp_line
			(start 0.800001 -0.399999)
			(end -0.800001 -0.399999)
			(stroke
				(width 0.1)
				(type default)
			)
			(layer "F.Fab")
		)
		(fp_line
			(start -0.800001 0.399999)
			(end 0.800001 0.399999)
			(stroke
				(width 0.1)
				(type default)
			)
			(layer "F.Fab")
		)
		(fp_line
			(start -0.800001 -0.399999)
			(end -0.800001 0.399999)
			(stroke
				(width 0.1)
				(type default)
			)
			(layer "F.Fab")
		)
		(pad "1" smd rect
			(at -0.650001 0 180)
			(size 0.7112 0.8128)
			(layers "F.Cu" "F.Mask" "F.Paste")
			(net "P3V3_B2_QSFP")
		)
		(pad "2" smd rect
			(at 0.650001 0)
			(size 0.7112 0.8128)
			(layers "F.Cu" "F.Mask" "F.Paste")
			(net "P3V3_40G_B2_VCC_TX")
		)
	)
	(footprint ""
		(layer "F.Cu")
		(at -268.224 9.017 -90)
		(property "Reference" "C31"
			(at 0.99822 -1.50114 0)
			(unlocked yes)
			(layer "F.SilkS")
			(effects
				(font
					(size 0.762 0.5334)
					(thickness 0.1016)
				)
			)
		)
		(property "Value" ""
			(at 0 0 270)
			(layer "F.Fab")
			(effects
				(font
					(size 1.27 1.27)
				)
			)
		)
		(duplicate_pad_numbers_are_jumpers no)
		(fp_poly
			(pts
				(xy -0.999299 0.504) (xy -0.999299 -0.503999) (xy 0.9993 -0.503999) (xy 0.9993 0.504)
			)
			(stroke
				(width 0)
				(type default)
			)
			(fill no)
			(layer "F.CrtYd")
		)
		(fp_line
			(start -0.499999 0.25)
			(end -0.499999 -0.249999)
			(stroke
				(width 0.1)
				(type default)
			)
			(layer "F.Fab")
		)
		(fp_line
			(start 0.499999 0.25)
			(end -0.499999 0.25)
			(stroke
				(width 0.1)
				(type default)
			)
			(layer "F.Fab")
		)
		(fp_line
			(start -0.499999 -0.249999)
			(end 0.499999 -0.249999)
			(stroke
				(width 0.1)
				(type default)
			)
			(layer "F.Fab")
		)
		(fp_line
			(start 0.499999 -0.249999)
			(end 0.499999 0.25)
			(stroke
				(width 0.1)
				(type default)
			)
			(layer "F.Fab")
		)
		(pad "1" smd rect
			(at -0.4572 0)
			(size 0.508 0.5842)
			(layers "F.Cu" "F.Mask" "F.Paste")
			(net "P3V3_40G_B1_VCC_TX")
		)
		(pad "2" smd rect
			(at 0.4572 0)
			(size 0.508 0.5842)
			(layers "F.Cu" "F.Mask" "F.Paste")
			(net "GND")
		)
	)
	(footprint ""
		(layer "F.Cu")
		(at -61.785401 44.869202 90)
		(property "Reference" "R41"
			(at 4.102202 0.228501 90)
			(unlocked yes)
			(layer "F.SilkS")
			(effects
				(font
					(size 0.762 0.5334)
					(thickness 0.1016)
				)
			)
		)
		(property "Value" ""
			(at 0 0 90)
			(layer "F.Fab")
			(effects
				(font
					(size 1.27 1.27)
				)
			)
		)
		(duplicate_pad_numbers_are_jumpers no)
		(fp_line
			(start 0 -0.381)
			(end 0 0.381)
			(stroke
				(width 0.127)
				(type default)
			)
			(layer "F.SilkS")
		)
		(fp_poly
			(pts
				(xy 1.255601 0.6564) (xy -1.2556 0.6564) (xy -1.2556 -0.656399) (xy 1.255601 -0.656399)
			)
			(stroke
				(width 0)
				(type default)
			)
			(fill no)
			(layer "F.CrtYd")
		)
		(fp_line
			(start 0.800001 -0.399999)
			(end -0.800001 -0.399999)
			(stroke
				(width 0.1)
				(type default)
			)
			(layer "F.Fab")
		)
		(fp_line
			(start -0.800001 -0.399999)
			(end -0.800001 0.399999)
			(stroke
				(width 0.1)
				(type default)
			)
			(layer "F.Fab")
		)
		(fp_line
			(start 0.800001 0.399999)
			(end 0.800001 -0.399999)
			(stroke
				(width 0.1)
				(type default)
			)
			(layer "F.Fab")
		)
		(fp_line
			(start -0.800001 0.399999)
			(end 0.800001 0.399999)
			(stroke
				(width 0.1)
				(type default)
			)
			(layer "F.Fab")
		)
		(pad "1" smd rect
			(at -0.650001 0 90)
			(size 0.7112 0.8128)
			(layers "F.Cu" "F.Mask" "F.Paste")
			(net "P3V3_B2_QSFP")
		)
		(pad "2" smd rect
			(at 0.650001 0 270)
			(size 0.7112 0.8128)
			(layers "F.Cu" "F.Mask" "F.Paste")
			(net "P3V3_10G_B2_VCCR")
		)
	)
	(footprint ""
		(layer "F.Cu")
		(at 1.749999 42.660001)
		(property "Reference" "MH6"
			(at 0 -4.9149 0)
			(unlocked yes)
			(layer "F.SilkS")
			(effects
				(font
					(size 0.762 0.5334)
					(thickness 0.1016)
				)
			)
		)
		(property "Value" ""
			(at 0 0 0)
			(layer "F.Fab")
			(effects
				(font
					(size 1.27 1.27)
				)
			)
		)
		(duplicate_pad_numbers_are_jumpers no)
		(fp_poly
			(pts
				(arc
					(start 4.0132 0)
					(mid -4.0132 0)
					(end 4.0132 0)
				)
			)
			(stroke
				(width 0)
				(type default)
			)
			(fill no)
			(layer "B.CrtYd")
		)
		(fp_poly
			(pts
				(arc
					(start 4.0132 0)
					(mid -4.0132 0)
					(end 4.0132 0)
				)
			)
			(stroke
				(width 0)
				(type default)
			)
			(fill no)
			(layer "F.CrtYd")
		)
		(pad "1" thru_hole circle
			(at 0 0)
			(size 7.0104 7.0104)
			(drill 3.5052)
			(layers "*.Cu" "*.Mask")
			(remove_unused_layers no)
			(net "GND")
			(padstack
				(mode front_inner_back)
				(layer "Inner"
					(shape circle)
					(size 4.5212 4.5212)
				)
				(layer "B.Cu"
					(shape circle)
					(size 7.0104 7.0104)
				)
			)
		)
		(pad "2" thru_hole circle
			(at 0 -2.794)
			(size 0.6604 0.6604)
			(drill 0.3556)
			(layers "*.Cu" "*.Mask")
			(remove_unused_layers no)
			(net "GND")
		)
		(pad "3" thru_hole circle
			(at -1.905 -2.032)
			(size 0.6604 0.6604)
			(drill 0.3556)
			(layers "*.Cu" "*.Mask")
			(remove_unused_layers no)
			(net "GND")
		)
		(pad "4" thru_hole circle
			(at -2.794 0)
			(size 0.6604 0.6604)
			(drill 0.3556)
			(layers "*.Cu" "*.Mask")
			(remove_unused_layers no)
			(net "GND")
		)
		(pad "5" thru_hole circle
			(at -2.032 1.905)
			(size 0.6604 0.6604)
			(drill 0.3556)
			(layers "*.Cu" "*.Mask")
			(remove_unused_layers no)
			(net "GND")
		)
		(pad "6" thru_hole circle
			(at 0 2.794)
			(size 0.6604 0.6604)
			(drill 0.3556)
			(layers "*.Cu" "*.Mask")
			(remove_unused_layers no)
			(net "GND")
		)
		(pad "7" thru_hole circle
			(at 2.032 1.905)
			(size 0.6604 0.6604)
			(drill 0.3556)
			(layers "*.Cu" "*.Mask")
			(remove_unused_layers no)
			(net "GND")
		)
		(pad "8" thru_hole circle
			(at 2.794 0)
			(size 0.6604 0.6604)
			(drill 0.3556)
			(layers "*.Cu" "*.Mask")
			(remove_unused_layers no)
			(net "GND")
		)
		(pad "9" thru_hole circle
			(at 1.905 -2.032)
			(size 0.6604 0.6604)
			(drill 0.3556)
			(layers "*.Cu" "*.Mask")
			(remove_unused_layers no)
			(net "GND")
		)
	)
	(footprint ""
		(layer "F.Cu")
		(at -45.109699 20.000001)
		(property "Reference" "MH5"
			(at 0.011999 -4.229141 0)
			(unlocked yes)
			(layer "F.SilkS")
			(effects
				(font
					(size 0.762 0.5334)
					(thickness 0.1016)
				)
			)
		)
		(property "Value" ""
			(at 0 0 0)
			(layer "F.Fab")
			(effects
				(font
					(size 1.27 1.27)
				)
			)
		)
		(duplicate_pad_numbers_are_jumpers no)
		(fp_poly
			(pts
				(arc
					(start 4.0132 0)
					(mid -4.0132 0)
					(end 4.0132 0)
				)
			)
			(stroke
				(width 0)
				(type default)
			)
			(fill no)
			(layer "B.CrtYd")
		)
		(fp_poly
			(pts
				(arc
					(start 4.0132 0)
					(mid -4.0132 0)
					(end 4.0132 0)
				)
			)
			(stroke
				(width 0)
				(type default)
			)
			(fill no)
			(layer "F.CrtYd")
		)
		(pad "1" thru_hole circle
			(at 0 0)
			(size 7.0104 7.0104)
			(drill 3.5052)
			(layers "*.Cu" "*.Mask")
			(remove_unused_layers no)
			(net "GND")
			(padstack
				(mode front_inner_back)
				(layer "Inner"
					(shape circle)
					(size 4.5212 4.5212)
				)
				(layer "B.Cu"
					(shape circle)
					(size 7.0104 7.0104)
				)
			)
		)
		(pad "2" thru_hole circle
			(at 0 -2.794)
			(size 0.6604 0.6604)
			(drill 0.3556)
			(layers "*.Cu" "*.Mask")
			(remove_unused_layers no)
			(net "GND")
		)
		(pad "3" thru_hole circle
			(at -1.905 -2.032)
			(size 0.6604 0.6604)
			(drill 0.3556)
			(layers "*.Cu" "*.Mask")
			(remove_unused_layers no)
			(net "GND")
		)
		(pad "4" thru_hole circle
			(at -2.794 0)
			(size 0.6604 0.6604)
			(drill 0.3556)
			(layers "*.Cu" "*.Mask")
			(remove_unused_layers no)
			(net "GND")
		)
		(pad "5" thru_hole circle
			(at -2.032 1.905)
			(size 0.6604 0.6604)
			(drill 0.3556)
			(layers "*.Cu" "*.Mask")
			(remove_unused_layers no)
			(net "GND")
		)
		(pad "6" thru_hole circle
			(at 0 2.794)
			(size 0.6604 0.6604)
			(drill 0.3556)
			(layers "*.Cu" "*.Mask")
			(remove_unused_layers no)
			(net "GND")
		)
		(pad "7" thru_hole circle
			(at 2.032 1.905)
			(size 0.6604 0.6604)
			(drill 0.3556)
			(layers "*.Cu" "*.Mask")
			(remove_unused_layers no)
			(net "GND")
		)
		(pad "8" thru_hole circle
			(at 2.794 0)
			(size 0.6604 0.6604)
			(drill 0.3556)
			(layers "*.Cu" "*.Mask")
			(remove_unused_layers no)
			(net "GND")
		)
		(pad "9" thru_hole circle
			(at 1.905 -2.032)
			(size 0.6604 0.6604)
			(drill 0.3556)
			(layers "*.Cu" "*.Mask")
			(remove_unused_layers no)
			(net "GND")
		)
	)
	(footprint ""
		(layer "F.Cu")
		(at -45.631001 13.297002)
		(property "Reference" "R60"
			(at 0.419001 1.219098 0)
			(unlocked yes)
			(layer "F.SilkS")
			(effects
				(font
					(size 0.762 0.5334)
					(thickness 0.1016)
				)
			)
		)
		(property "Value" ""
			(at 0 0 0)
			(layer "F.Fab")
			(effects
				(font
					(size 1.27 1.27)
				)
			)
		)
		(duplicate_pad_numbers_are_jumpers no)
		(fp_line
			(start 0 -0.381)
			(end 0 0.381)
			(stroke
				(width 0.127)
				(type default)
			)
			(layer "F.SilkS")
		)
		(fp_poly
			(pts
				(xy 1.255601 0.656399) (xy -1.255601 0.656399) (xy -1.255601 -0.6564) (xy 1.255601 -0.6564)
			)
			(stroke
				(width 0)
				(type default)
			)
			(fill no)
			(layer "F.CrtYd")
		)
		(fp_line
			(start -0.800001 -0.4)
			(end -0.800001 0.399999)
			(stroke
				(width 0.1)
				(type default)
			)
			(layer "F.Fab")
		)
		(fp_line
			(start -0.800001 0.399999)
			(end 0.800001 0.399999)
			(stroke
				(width 0.1)
				(type default)
			)
			(layer "F.Fab")
		)
		(fp_line
			(start 0.800001 -0.4)
			(end -0.800001 -0.4)
			(stroke
				(width 0.1)
				(type default)
			)
			(layer "F.Fab")
		)
		(fp_line
			(start 0.800001 0.399999)
			(end 0.800001 -0.4)
			(stroke
				(width 0.1)
				(type default)
			)
			(layer "F.Fab")
		)
		(pad "1" smd rect
			(at -0.650001 0)
			(size 0.7112 0.8128)
			(layers "F.Cu" "F.Mask" "F.Paste")
			(net "P3V3_40G_B2_VCC1")
		)
		(pad "2" smd rect
			(at 0.650001 0 180)
			(size 0.7112 0.8128)
			(layers "F.Cu" "F.Mask" "F.Paste")
			(net "P3V3_B2_QSFP")
		)
	)
)
